# S9S_MB_2U (Grand Teton) — schematic netlist excerpt (pin names and nets, part order shuffled) for the footprints in the layout excerpt that follows; sources: Cadence DE-HDL packaged netlist, KiCad conversion of 03242023_DA0F0TMBIJ0_F0T_Motherboard_J_brd_V01_OCP.brd

C974  Q_CAP  10UF 6.3V 20% X6S  pkg C0402  page 74 : A = PVCCIN_CPU0 ; B = GND
R144  Q_RES  0 5% CHIP  pkg 0402LF  page 197 : A = PECI_BMC ; B = PECI_BMC_R

(kicad_pcb
	(version 20260206)
	(generator "pcbnew")
	(generator_version "10.0")
	(general
		(thickness 1.6)
		(legacy_teardrops no)
	)
	(paper "A4")
	(title_block
		(title "03242023_DA0F0TMBIJ0_F0T_Motherboard_J_brd_V01_OCP.brd")
		(comment 1 "Grand Teton / footprints 3546-3547 of 6105")
	)
	(layers
		(0 "F.Cu" signal "TOP")
		(4 "In1.Cu" signal "GND")
		(6 "In2.Cu" signal "IN1")
		(8 "In3.Cu" signal "GND1")
		(10 "In4.Cu" signal "IN2")
		(12 "In5.Cu" signal "GND2")
		(14 "In6.Cu" signal "IN3")
		(16 "In7.Cu" signal "GND3")
		(18 "In8.Cu" signal "VCC")
		(20 "In9.Cu" signal "VCC1")
		(22 "In10.Cu" signal "GND4")
		(24 "In11.Cu" signal "IN4")
		(26 "In12.Cu" signal "GND5")
		(28 "In13.Cu" signal "IN5")
		(30 "In14.Cu" signal "GND6")
		(32 "In15.Cu" signal "IN6")
		(34 "In16.Cu" signal "GND7")
		(2 "B.Cu" signal "BOTTOM")
		(9 "F.Adhes" user "F.Adhesive")
		(11 "B.Adhes" user "B.Adhesive")
		(13 "F.Paste" user "Package Geometry/Pastemask Top")
		(15 "B.Paste" user "Package Geometry/Pastemask Bottom")
		(5 "F.SilkS" user "Ref Des/Silkscreen Top")
		(7 "B.SilkS" user "Ref Des/Silkscreen Bottom")
		(1 "F.Mask" user "Board Geometry/Soldermask Top")
		(3 "B.Mask" user "Board Geometry/Soldermask Bottom")
		(17 "Dwgs.User" user "User.Drawings")
		(19 "Cmts.User" user "User.Comments")
		(21 "Eco1.User" user "User.Eco1")
		(23 "Eco2.User" user "User.Eco2")
		(25 "Edge.Cuts" user "Board Geometry/Outline")
		(27 "Margin" user)
		(31 "F.CrtYd" user "Package Geometry/Place Bound Top")
		(29 "B.CrtYd" user "Package Geometry/Place Bound Bottom")
		(35 "F.Fab" user "Ref Des/Assembly Top")
		(33 "B.Fab" user "Ref Des/Assembly Bottom")
	)
	(footprint ""
		(layer "F.Cu")
		(at 354.251514 -256.654046 -90)
		(property "Reference" "C974"
			(at 0 0 270)
			(layer "F.SilkS")
			(hide yes)
			(effects
				(font
					(size 1.27 1.27)
				)
			)
		)
		(property "Value" ""
			(at 0 0 270)
			(layer "F.Fab")
			(effects
				(font
					(size 1.27 1.27)
				)
			)
		)
		(duplicate_pad_numbers_are_jumpers no)
		(fp_line
			(start -0.7874 0.4064)
			(end -0.7874 -0.4064)
			(stroke
				(width 0.1524)
				(type default)
			)
			(layer "F.SilkS")
		)
		(fp_line
			(start 0.7874 0.4064)
			(end -0.7874 0.4064)
			(stroke
				(width 0.1524)
				(type default)
			)
			(layer "F.SilkS")
		)
		(fp_line
			(start -0.7874 -0.4064)
			(end 0.7874 -0.4064)
			(stroke
				(width 0.1524)
				(type default)
			)
			(layer "F.SilkS")
		)
		(fp_line
			(start 0.7874 -0.4064)
			(end 0.7874 0.4064)
			(stroke
				(width 0.1524)
				(type default)
			)
			(layer "F.SilkS")
		)
		(fp_line
			(start -0.67945 0.3048)
			(end -0.67945 -0.305054)
			(stroke
				(width 0.1)
				(type default)
			)
			(layer "F.Fab")
		)
		(fp_line
			(start -0.12065 0.3048)
			(end -0.67945 0.3048)
			(stroke
				(width 0.1)
				(type default)
			)
			(layer "F.Fab")
		)
		(fp_line
			(start 0.120396 0.3048)
			(end 0.120396 0.2794)
			(stroke
				(width 0.1)
				(type default)
			)
			(layer "F.Fab")
		)
		(fp_line
			(start 0.67945 0.3048)
			(end 0.120396 0.3048)
			(stroke
				(width 0.1)
				(type default)
			)
			(layer "F.Fab")
		)
		(fp_line
			(start -0.12065 0.2794)
			(end -0.12065 0.3048)
			(stroke
				(width 0.1)
				(type default)
			)
			(layer "F.Fab")
		)
		(fp_line
			(start 0.120396 0.2794)
			(end -0.12065 0.2794)
			(stroke
				(width 0.1)
				(type default)
			)
			(layer "F.Fab")
		)
		(fp_line
			(start -0.12065 -0.2794)
			(end 0.12065 -0.2794)
			(stroke
				(width 0.1)
				(type default)
			)
			(layer "F.Fab")
		)
		(fp_line
			(start 0.12065 -0.2794)
			(end 0.12065 -0.3048)
			(stroke
				(width 0.1)
				(type default)
			)
			(layer "F.Fab")
		)
		(fp_line
			(start 0.12065 -0.3048)
			(end 0.67945 -0.3048)
			(stroke
				(width 0.1)
				(type default)
			)
			(layer "F.Fab")
		)
		(fp_line
			(start 0.67945 -0.3048)
			(end 0.67945 0.3048)
			(stroke
				(width 0.1)
				(type default)
			)
			(layer "F.Fab")
		)
		(fp_line
			(start -0.67945 -0.305054)
			(end -0.12065 -0.305054)
			(stroke
				(width 0.1)
				(type default)
			)
			(layer "F.Fab")
		)
		(fp_line
			(start -0.12065 -0.305054)
			(end -0.12065 -0.2794)
			(stroke
				(width 0.1)
				(type default)
			)
			(layer "F.Fab")
		)
		(pad "1" smd circle
			(at -0.40005 0 270)
			(size 0 0)
			(layers "F.Cu" "F.Mask" "F.Paste")
			(net "PVCCIN_CPU0")
		)
		(pad "2" smd circle
			(at 0.40005 0 270)
			(size 0 0)
			(layers "F.Cu" "F.Mask" "F.Paste")
			(net "GND")
		)
	)
	(footprint ""
		(layer "F.Cu")
		(at 166.37 -23.713948 90)
		(property "Reference" "R144"
			(at 0 0 90)
			(layer "F.SilkS")
			(hide yes)
			(effects
				(font
					(size 1.27 1.27)
				)
			)
		)
		(property "Value" ""
			(at 0 0 90)
			(layer "F.Fab")
			(effects
				(font
					(size 1.27 1.27)
				)
			)
		)
		(duplicate_pad_numbers_are_jumpers no)
		(fp_line
			(start 0.7874 -0.4064)
			(end 0.7874 0.4064)
			(stroke
				(width 0.1524)
				(type default)
			)
			(layer "F.SilkS")
		)
		(fp_line
			(start -0.7874 -0.4064)
			(end 0.7874 -0.4064)
			(stroke
				(width 0.1524)
				(type default)
			)
			(layer "F.SilkS")
		)
		(fp_line
			(start 0.7874 0.4064)
			(end -0.7874 0.4064)
			(stroke
				(width 0.1524)
				(type default)
			)
			(layer "F.SilkS")
		)
		(fp_line
			(start -0.7874 0.4064)
			(end -0.7874 -0.4064)
			(stroke
				(width 0.1524)
				(type default)
			)
			(layer "F.SilkS")
		)
		(fp_line
			(start -0.12065 -0.305054)
			(end -0.12065 -0.2794)
			(stroke
				(width 0.1)
				(type default)
			)
			(layer "F.Fab")
		)
		(fp_line
			(start -0.67945 -0.305054)
			(end -0.12065 -0.305054)
			(stroke
				(width 0.1)
				(type default)
			)
			(layer "F.Fab")
		)
		(fp_line
			(start 0.67945 -0.3048)
			(end 0.67945 0.3048)
			(stroke
				(width 0.1)
				(type default)
			)
			(layer "F.Fab")
		)
		(fp_line
			(start 0.12065 -0.3048)
			(end 0.67945 -0.3048)
			(stroke
				(width 0.1)
				(type default)
			)
			(layer "F.Fab")
		)
		(fp_line
			(start 0.12065 -0.2794)
			(end 0.12065 -0.3048)
			(stroke
				(width 0.1)
				(type default)
			)
			(layer "F.Fab")
		)
		(fp_line
			(start -0.12065 -0.2794)
			(end 0.12065 -0.2794)
			(stroke
				(width 0.1)
				(type default)
			)
			(layer "F.Fab")
		)
		(fp_line
			(start 0.120396 0.2794)
			(end -0.12065 0.2794)
			(stroke
				(width 0.1)
				(type default)
			)
			(layer "F.Fab")
		)
		(fp_line
			(start -0.12065 0.2794)
			(end -0.12065 0.3048)
			(stroke
				(width 0.1)
				(type default)
			)
			(layer "F.Fab")
		)
		(fp_line
			(start 0.67945 0.3048)
			(end 0.120396 0.3048)
			(stroke
				(width 0.1)
				(type default)
			)
			(layer "F.Fab")
		)
		(fp_line
			(start 0.120396 0.3048)
			(end 0.120396 0.2794)
			(stroke
				(width 0.1)
				(type default)
			)
			(layer "F.Fab")
		)
		(fp_line
			(start -0.12065 0.3048)
			(end -0.67945 0.3048)
			(stroke
				(width 0.1)
				(type default)
			)
			(layer "F.Fab")
		)
		(fp_line
			(start -0.67945 0.3048)
			(end -0.67945 -0.305054)
			(stroke
				(width 0.1)
				(type default)
			)
			(layer "F.Fab")
		)
		(pad "1" smd circle
			(at -0.40005 0 90)
			(size 0 0)
			(layers "F.Cu" "F.Mask" "F.Paste")
			(net "PECI_BMC")
		)
		(pad "2" smd circle
			(at 0.40005 0 90)
			(size 0 0)
			(layers "F.Cu" "F.Mask" "F.Paste")
			(net "PECI_BMC_R")
		)
	)
)
